FILE_TYPE = MACRO_DRAWING;
SET COLOR_WIRE YELLOW;
SET COLOR_PROP ORANGE;
SET COLOR_DOT WHITE;
SET COLOR_ARC YELLOW;
SET COLOR_BODY GREEN;
SET COLOR_NOTE PURPLE;
SET PROP_DISPLAY VALUE;
SET PAGE_NUMBER P9;
FORCEADD QUANTA_TITLE_BLOCK_C..1
(5550 -1600);
FORCEPROP 1 LAST CUSTOM_TXT_CDS <NAME_2>
J 0
(2375 -1550);
FORCEPROP 1 LAST CUSTOM_TXT_CDS <NAME_1>
J 0
(2375 -1425);
FORCEPROP 1 LAST CUSTOM_TXT_CDS <Q_NUMBER>
J 0
(4147 -1497);
DISPLAY 1.212766 (4147 -1497);
FORCEPROP 1 LAST CUSTOM_TXT_CDS <Q_PROJ>
J 0
(3168 -1498);
DISPLAY 1.212766 (3168 -1498);
FORCEPROP 1 LAST CUSTOM_TXT_CDS <Q_REV>
J 0
(5366 -1497);
DISPLAY 1.212766 (5366 -1497);
FORCEPROP 1 LAST CUSTOM_TXT_CDS <CON_LAST_MODIFIED>
J 0
(3665 -1585);
DISPLAY 0.978723 (3665 -1585);
FORCEPROP 1 LAST CUSTOM_TXT_CDS <CON_PAGE_NUM> OF <CON_TOTAL_PAGES>
J 0
(5104 -1582);
DISPLAY 0.978723 (5104 -1582);
FORCEPROP 1 LAST Q_TITLE BLOCK DIAGRAM - SMBUS
J 0
(-3816 -1574);
DISPLAY 2.446809 (-3816 -1574);
PAINT GREEN (-3816 -1574);
FORCEPROP 1 LAST Q_DEPT 
J 1
(1787 -1551);
DISPLAY 1.957447 (1787 -1551);
PAINT GREEN (1787 -1551);
FORCEPROP 2 LAST CDS_LIB pure_quanta
J 0
(5550 -1600);
PAINT MONO (5550 -1600);
DISPLAY INVISIBLE (5550 -1600);
FORCEPROP 1 LAST CDS_LMAN_SYM_OUTLINE -9475,6775,100,-125
J 0
(5550 -1600);
DISPLAY 0.468085 (5550 -1600);
PAINT GREEN (5550 -1600);
DISPLAY INVISIBLE (5550 -1600);
FORCEPROP 2 LAST PAGE_BORDER TRUE
J 0
(-2340 3650);
DISPLAY 0.638298 (-2340 3650);
PAINT PINK (-2340 3650);
DISPLAY INVISIBLE (-2340 3650);
FORCEPROP 1 LAST COMMENT_BODY TRUE
J 0
(5562 -1613);
DISPLAY 0.978723 (5562 -1613);
PAINT GREEN (5562 -1613);
DISPLAY INVISIBLE (5562 -1613);
FORCEPROP 2 LAST CDS_XR_PAGE_TITLE CR-9 : @S9S_MB_2U_LIB.S9S_MB_2U(SCH_1):PAGE9
J 0
(-2340 3650);
DISPLAY 0.638298 (-2340 3650);
PAINT PINK (-2340 3650);
DISPLAY INVISIBLE (-2340 3650);
FORCEPROP 2 LAST CUSTOM_TXT_CDS <XR_PAGE_TITLE>
J 0
(-2340 3650);
DISPLAY 0.638298 (-2340 3650);
PAINT PINK (-2340 3650);
DISPLAY INVISIBLE (-2340 3650);
FORCEPROP 0 LAST CDS_CON_LAST_MODIFIED Thu Aug 24 16:12:00 2023
J 0
(3665 -1585);
PAINT MONO (3665 -1585);
DISPLAY INVISIBLE (3665 -1585);
FORCENOTE
$CDS_IMAGE|F0T_diagram_MB_20220309_rev1-SMB_2nd source (3).jpg|9251|5074
(875 1850) 0;
DISPLAY LEFT (875 1850);
QUIT
